(kicad_pcb
	(version 20260206)
	(generator "pcbnew")
	(generator_version "10.0")
	(general
		(thickness 1.6)
		(legacy_teardrops no)
	)
	(paper "A4")
	(title_block
		(title "04192023_DAF0TMB3IC0_F0TG_MB_C_brd_V02_OCP.brd")
		(comment 1 "Grand Teton / footprints 3671-3675 of 8354")
	)
	(layers
		(0 "F.Cu" signal "TOP")
		(4 "In1.Cu" signal "GND")
		(6 "In2.Cu" signal "IN1")
		(8 "In3.Cu" signal "GND1")
		(10 "In4.Cu" signal "IN2")
		(12 "In5.Cu" signal "GND2")
		(14 "In6.Cu" signal "IN3")
		(16 "In7.Cu" signal "GND3")
		(18 "In8.Cu" signal "VCC")
		(20 "In9.Cu" signal "VCC1")
		(22 "In10.Cu" signal "GND4")
		(24 "In11.Cu" signal "IN4")
		(26 "In12.Cu" signal "GND5")
		(28 "In13.Cu" signal "IN5")
		(30 "In14.Cu" signal "GND6")
		(32 "In15.Cu" signal "IN6")
		(34 "In16.Cu" signal "GND7")
		(2 "B.Cu" signal "BOTTOM")
		(9 "F.Adhes" user "F.Adhesive")
		(11 "B.Adhes" user "B.Adhesive")
		(13 "F.Paste" user "Package Geometry/Pastemask Top")
		(15 "B.Paste" user "Package Geometry/Pastemask Bottom")
		(5 "F.SilkS" user "Ref Des/Silkscreen Top")
		(7 "B.SilkS" user "Ref Des/Silkscreen Bottom")
		(1 "F.Mask" user "Board Geometry/Soldermask Top")
		(3 "B.Mask" user "Board Geometry/Soldermask Bottom")
		(17 "Dwgs.User" user "User.Drawings")
		(19 "Cmts.User" user "User.Comments")
		(21 "Eco1.User" user "User.Eco1")
		(23 "Eco2.User" user "User.Eco2")
		(25 "Edge.Cuts" user "Board Geometry/Outline")
		(27 "Margin" user)
		(31 "F.CrtYd" user "Package Geometry/Place Bound Top")
		(29 "B.CrtYd" user "Package Geometry/Place Bound Bottom")
		(35 "F.Fab" user "Ref Des/Assembly Top")
		(33 "B.Fab" user "Ref Des/Assembly Bottom")
	)
	(footprint ""
		(layer "F.Cu")
		(at 70.409054 -335.000092)
		(property "Reference" "PU37"
			(at 2.996946 -8.508238 0)
			(unlocked yes)
			(layer "F.SilkS")
			(effects
				(font
					(size 0.7874 0.5842)
					(thickness 0.1524)
				)
				(justify left)
			)
		)
		(property "Value" ""
			(at 0 0 0)
			(layer "F.Fab")
			(effects
				(font
					(size 1.27 1.27)
				)
			)
		)
		(duplicate_pad_numbers_are_jumpers no)
		(fp_line
			(start -2.500122 -2.999994)
			(end -2.24409 -2.999994)
			(stroke
				(width 0.1524)
				(type default)
			)
			(layer "F.SilkS")
		)
		(fp_line
			(start -2.500122 -2.529078)
			(end -2.500122 -2.999994)
			(stroke
				(width 0.1524)
				(type default)
			)
			(layer "F.SilkS")
		)
		(fp_line
			(start -2.500122 0.6604)
			(end -2.500122 0.229108)
			(stroke
				(width 0.1524)
				(type default)
			)
			(layer "F.SilkS")
		)
		(fp_line
			(start -2.500122 2.999994)
			(end -2.500122 2.339594)
			(stroke
				(width 0.1524)
				(type default)
			)
			(layer "F.SilkS")
		)
		(fp_line
			(start -2.2987 2.999994)
			(end -2.500122 2.999994)
			(stroke
				(width 0.1524)
				(type default)
			)
			(layer "F.SilkS")
		)
		(fp_line
			(start 2.31394 -2.999994)
			(end 2.500122 -2.999994)
			(stroke
				(width 0.1524)
				(type default)
			)
			(layer "F.SilkS")
		)
		(fp_line
			(start 2.500122 -2.999994)
			(end 2.500122 -2.44348)
			(stroke
				(width 0.1524)
				(type default)
			)
			(layer "F.SilkS")
		)
		(fp_line
			(start 2.500122 2.339594)
			(end 2.500122 2.999994)
			(stroke
				(width 0.1524)
				(type default)
			)
			(layer "F.SilkS")
		)
		(fp_line
			(start 2.500122 2.999994)
			(end 2.2987 2.999994)
			(stroke
				(width 0.1524)
				(type default)
			)
			(layer "F.SilkS")
		)
		(fp_poly
			(pts
				(xy -2.749296 -2.412238) (xy -3.422904 -2.636774) (xy -2.973832 -3.085846)
			)
			(stroke
				(width 0)
				(type default)
			)
			(fill yes)
			(layer "F.SilkS")
		)
		(fp_line
			(start -2.500122 -2.999994)
			(end 2.500122 -2.999994)
			(stroke
				(width 0.1)
				(type default)
			)
			(layer "F.Fab")
		)
		(fp_line
			(start -2.500122 2.999994)
			(end -2.500122 -2.999994)
			(stroke
				(width 0.1)
				(type default)
			)
			(layer "F.Fab")
		)
		(fp_line
			(start 2.500122 -2.999994)
			(end 2.500122 2.999994)
			(stroke
				(width 0.1)
				(type default)
			)
			(layer "F.Fab")
		)
		(fp_line
			(start 2.500122 2.999994)
			(end -2.500122 2.999994)
			(stroke
				(width 0.1)
				(type default)
			)
			(layer "F.Fab")
		)
		(fp_poly
			(pts
				(xy -4.218432 -2.783078) (xy -4.218432 -1.767078) (xy -3.202432 -2.275078)
			)
			(stroke
				(width 0)
				(type default)
			)
			(fill yes)
			(layer "F.Fab")
		)
		(pad "1" smd rect
			(at -2.400046 -2.275078 90)
			(size 0.2286 0.6096)
			(layers "F.Cu" "F.Mask" "F.Paste")
			(net "PVDDCR_CPU1_P1_VOS3")
		)
		(pad "2" smd rect
			(at -2.400046 -1.82499 90)
			(size 0.2286 0.6096)
			(layers "F.Cu" "F.Mask" "F.Paste")
			(net "GND")
		)
		(pad "3" smd rect
			(at -2.400046 -1.374902 90)
			(size 0.2286 0.6096)
			(layers "F.Cu" "F.Mask" "F.Paste")
			(net "PVDDCR_CPU1_P1_VCC3")
		)
		(pad "4" smd rect
			(at -2.400046 -0.925068 90)
			(size 0.2286 0.6096)
			(layers "F.Cu" "F.Mask" "F.Paste")
			(net "PVDDCR_CPU1_P1_PVCC")
		)
		(pad "5" smd rect
			(at -2.400046 -0.47498 90)
			(size 0.2286 0.6096)
			(layers "F.Cu" "F.Mask" "F.Paste")
			(net "GND")
		)
		(pad "6" smd rect
			(at -2.400046 -0.024892 90)
			(size 0.2286 0.6096)
			(layers "F.Cu" "F.Mask" "F.Paste")
			(net "NC_PVDDCR_CPU1_P1_GL1_3")
		)
		(pad "7_9-20_24" smd circle
			(at 0 1.150112 90)
			(size 0 0)
			(layers "F.Cu" "F.Mask" "F.Paste")
			(net "GND")
		)
		(pad "10_19" smd rect
			(at 0 2.899918 90)
			(size 0.6096 4.318)
			(layers "F.Cu" "F.Mask" "F.Paste")
			(net "SW_PVDDCR_CPU1_P1_SW3")
		)
		(pad "25_29" smd rect
			(at 1.549908 -1.279906 270)
			(size 2.0574 2.3114)
			(layers "F.Cu" "F.Mask" "F.Paste")
			(net "SW_P12V_AUX_PVDDCR_CPU1_P1_FLT")
		)
		(pad "30" smd rect
			(at 2.05994 -2.899918)
			(size 0.2286 0.6096)
			(layers "F.Cu" "F.Mask" "F.Paste")
			(net "SW_P12V_AUX_PVDDCR_CPU1_P1_FLT")
		)
		(pad "31" smd rect
			(at 1.610106 -2.899918)
			(size 0.2286 0.6096)
			(layers "F.Cu" "F.Mask" "F.Paste")
			(net "NC_PVDDCR_CPU1_P1_DNC3")
		)
		(pad "32" smd rect
			(at 1.160018 -2.899918)
			(size 0.2286 0.6096)
			(layers "F.Cu" "F.Mask" "F.Paste")
			(net "SW_PVDDCR_CPU1_P1_BOOTR3")
		)
		(pad "33" smd rect
			(at 0.70993 -2.899918)
			(size 0.2286 0.6096)
			(layers "F.Cu" "F.Mask" "F.Paste")
			(net "SW_PVDDCR_CPU1_P1_BOOT3")
		)
		(pad "34" smd rect
			(at 0.260096 -2.899918)
			(size 0.2286 0.6096)
			(layers "F.Cu" "F.Mask" "F.Paste")
			(net "PVDDCR_CPU1_P1_PWM3")
		)
		(pad "35" smd rect
			(at -0.189992 -2.899918)
			(size 0.2286 0.6096)
			(layers "F.Cu" "F.Mask" "F.Paste")
			(net "PVDDCR_CPU1_P1_VCC3")
		)
		(pad "36" smd rect
			(at -0.64008 -2.899918)
			(size 0.2286 0.6096)
			(layers "F.Cu" "F.Mask" "F.Paste")
			(net "PVDDCR_CPU1_P1_TEMP0")
		)
		(pad "37" smd rect
			(at -1.089914 -2.899918)
			(size 0.2286 0.6096)
			(layers "F.Cu" "F.Mask" "F.Paste")
			(net "PVDDCR_CPU1_P1_LSET3")
		)
		(pad "38" smd rect
			(at -1.540002 -2.899918)
			(size 0.2286 0.6096)
			(layers "F.Cu" "F.Mask" "F.Paste")
			(net "PVDDCR_CPU1_P1_IMON3")
		)
		(pad "39" smd rect
			(at -1.99009 -2.899918)
			(size 0.2286 0.6096)
			(layers "F.Cu" "F.Mask" "F.Paste")
			(net "PVDDCR_CPU1_P1_VCCS")
		)
		(pad "40" smd rect
			(at -0.87503 -1.27508)
			(size 1.7526 1.9558)
			(layers "F.Cu" "F.Mask" "F.Paste")
			(net "GND")
		)
		(pad "41" smd rect
			(at -1.525016 0.249936 270)
			(size 0.3048 0.4572)
			(layers "F.Cu" "F.Mask" "F.Paste")
			(net "NC_PVDDCR_CPU1_P1_GL2_3")
		)
		(zone
			(layer "F.Cu")
			(hatch none 0.5)
			(connect_pads
				(clearance 0)
			)
			(min_thickness 0.25)
			(keepout
				(tracks not_allowed)
				(vias allowed)
				(pads allowed)
				(copperpour not_allowed)
				(footprints allowed)
			)
			(placement
				(enabled no)
				(sheetname "")
			)
			(fill
				(thermal_gap 0.5)
				(thermal_bridge_width 0.5)
				(island_removal_mode 0)
			)
			(polygon
				(pts
					(xy 67.908932 -332.417674) (xy 67.908932 -332.749398) (xy 72.909176 -332.749398) (xy 72.909176 -332.411578)
					(xy 72.618854 -332.411578) (xy 72.618854 -332.455774) (xy 68.199254 -332.455774) (xy 68.199254 -332.417674)
				)
			)
		)
		(zone
			(layer "F.Cu")
			(hatch none 0.5)
			(connect_pads
				(clearance 0)
			)
			(min_thickness 0.25)
			(keepout
				(tracks not_allowed)
				(vias allowed)
				(pads allowed)
				(copperpour not_allowed)
				(footprints allowed)
			)
			(placement
				(enabled no)
				(sheetname "")
			)
			(fill
				(thermal_gap 0.5)
				(thermal_bridge_width 0.5)
				(island_removal_mode 0)
			)
			(polygon
				(pts
					(xy 70.461124 -335.246472) (xy 70.461124 -337.303872) (xy 68.606924 -337.303872) (xy 68.606924 -337.062826)
					(xy 68.364608 -337.062826) (xy 68.364608 -337.54441) (xy 72.286368 -337.54441) (xy 72.286368 -337.359498)
					(xy 70.752462 -337.359498) (xy 70.752462 -335.200498) (xy 72.909176 -335.200498) (xy 72.909176 -334.950816)
					(xy 70.75678 -334.950816)
				)
			)
		)
	)
	(footprint ""
		(layer "F.Cu")
		(at 43.1419 -100.34016 180)
		(property "Reference" "R700"
			(at 0 0 180)
			(layer "F.SilkS")
			(hide yes)
			(effects
				(font
					(size 1.27 1.27)
				)
			)
		)
		(property "Value" ""
			(at 0 0 180)
			(layer "F.Fab")
			(effects
				(font
					(size 1.27 1.27)
				)
			)
		)
		(duplicate_pad_numbers_are_jumpers no)
		(fp_line
			(start 0.7874 0.4064)
			(end -0.7874 0.4064)
			(stroke
				(width 0.1524)
				(type default)
			)
			(layer "F.SilkS")
		)
		(fp_line
			(start 0.7874 -0.4064)
			(end 0.7874 0.4064)
			(stroke
				(width 0.1524)
				(type default)
			)
			(layer "F.SilkS")
		)
		(fp_line
			(start -0.7874 0.4064)
			(end -0.7874 -0.4064)
			(stroke
				(width 0.1524)
				(type default)
			)
			(layer "F.SilkS")
		)
		(fp_line
			(start -0.7874 -0.4064)
			(end 0.7874 -0.4064)
			(stroke
				(width 0.1524)
				(type default)
			)
			(layer "F.SilkS")
		)
		(fp_line
			(start 0.67945 0.3048)
			(end 0.120396 0.3048)
			(stroke
				(width 0.1)
				(type default)
			)
			(layer "F.Fab")
		)
		(fp_line
			(start 0.67945 -0.3048)
			(end 0.67945 0.3048)
			(stroke
				(width 0.1)
				(type default)
			)
			(layer "F.Fab")
		)
		(fp_line
			(start 0.12065 -0.2794)
			(end 0.12065 -0.3048)
			(stroke
				(width 0.1)
				(type default)
			)
			(layer "F.Fab")
		)
		(fp_line
			(start 0.12065 -0.3048)
			(end 0.67945 -0.3048)
			(stroke
				(width 0.1)
				(type default)
			)
			(layer "F.Fab")
		)
		(fp_line
			(start 0.120396 0.3048)
			(end 0.120396 0.2794)
			(stroke
				(width 0.1)
				(type default)
			)
			(layer "F.Fab")
		)
		(fp_line
			(start 0.120396 0.2794)
			(end -0.12065 0.2794)
			(stroke
				(width 0.1)
				(type default)
			)
			(layer "F.Fab")
		)
		(fp_line
			(start -0.12065 0.3048)
			(end -0.67945 0.3048)
			(stroke
				(width 0.1)
				(type default)
			)
			(layer "F.Fab")
		)
		(fp_line
			(start -0.12065 0.2794)
			(end -0.12065 0.3048)
			(stroke
				(width 0.1)
				(type default)
			)
			(layer "F.Fab")
		)
		(fp_line
			(start -0.12065 -0.2794)
			(end 0.12065 -0.2794)
			(stroke
				(width 0.1)
				(type default)
			)
			(layer "F.Fab")
		)
		(fp_line
			(start -0.12065 -0.305054)
			(end -0.12065 -0.2794)
			(stroke
				(width 0.1)
				(type default)
			)
			(layer "F.Fab")
		)
		(fp_line
			(start -0.67945 0.3048)
			(end -0.67945 -0.305054)
			(stroke
				(width 0.1)
				(type default)
			)
			(layer "F.Fab")
		)
		(fp_line
			(start -0.67945 -0.305054)
			(end -0.12065 -0.305054)
			(stroke
				(width 0.1)
				(type default)
			)
			(layer "F.Fab")
		)
		(pad "1" smd circle
			(at -0.40005 0 180)
			(size 0 0)
			(layers "F.Cu" "F.Mask" "F.Paste")
			(net "P12V_AUX")
		)
		(pad "2" smd circle
			(at 0.40005 0 180)
			(size 0 0)
			(layers "F.Cu" "F.Mask" "F.Paste")
			(net "P12V_AUX_DSC_VOL")
		)
	)
	(footprint ""
		(layer "F.Cu")
		(at 160.40227 -73.24217 -90)
		(property "Reference" "R1311"
			(at 0 0 270)
			(layer "F.SilkS")
			(hide yes)
			(effects
				(font
					(size 1.27 1.27)
				)
			)
		)
		(property "Value" ""
			(at 0 0 270)
			(layer "F.Fab")
			(effects
				(font
					(size 1.27 1.27)
				)
			)
		)
		(duplicate_pad_numbers_are_jumpers no)
		(fp_line
			(start -0.7874 0.4064)
			(end -0.7874 -0.4064)
			(stroke
				(width 0.1524)
				(type default)
			)
			(layer "F.SilkS")
		)
		(fp_line
			(start 0.7874 0.4064)
			(end -0.7874 0.4064)
			(stroke
				(width 0.1524)
				(type default)
			)
			(layer "F.SilkS")
		)
		(fp_line
			(start -0.7874 -0.4064)
			(end 0.7874 -0.4064)
			(stroke
				(width 0.1524)
				(type default)
			)
			(layer "F.SilkS")
		)
		(fp_line
			(start 0.7874 -0.4064)
			(end 0.7874 0.4064)
			(stroke
				(width 0.1524)
				(type default)
			)
			(layer "F.SilkS")
		)
		(fp_line
			(start -0.67945 0.3048)
			(end -0.67945 -0.305054)
			(stroke
				(width 0.1)
				(type default)
			)
			(layer "F.Fab")
		)
		(fp_line
			(start -0.12065 0.3048)
			(end -0.67945 0.3048)
			(stroke
				(width 0.1)
				(type default)
			)
			(layer "F.Fab")
		)
		(fp_line
			(start 0.120396 0.3048)
			(end 0.120396 0.2794)
			(stroke
				(width 0.1)
				(type default)
			)
			(layer "F.Fab")
		)
		(fp_line
			(start 0.67945 0.3048)
			(end 0.120396 0.3048)
			(stroke
				(width 0.1)
				(type default)
			)
			(layer "F.Fab")
		)
		(fp_line
			(start -0.12065 0.2794)
			(end -0.12065 0.3048)
			(stroke
				(width 0.1)
				(type default)
			)
			(layer "F.Fab")
		)
		(fp_line
			(start 0.120396 0.2794)
			(end -0.12065 0.2794)
			(stroke
				(width 0.1)
				(type default)
			)
			(layer "F.Fab")
		)
		(fp_line
			(start -0.12065 -0.2794)
			(end 0.12065 -0.2794)
			(stroke
				(width 0.1)
				(type default)
			)
			(layer "F.Fab")
		)
		(fp_line
			(start 0.12065 -0.2794)
			(end 0.12065 -0.3048)
			(stroke
				(width 0.1)
				(type default)
			)
			(layer "F.Fab")
		)
		(fp_line
			(start 0.12065 -0.3048)
			(end 0.67945 -0.3048)
			(stroke
				(width 0.1)
				(type default)
			)
			(layer "F.Fab")
		)
		(fp_line
			(start 0.67945 -0.3048)
			(end 0.67945 0.3048)
			(stroke
				(width 0.1)
				(type default)
			)
			(layer "F.Fab")
		)
		(fp_line
			(start -0.67945 -0.305054)
			(end -0.12065 -0.305054)
			(stroke
				(width 0.1)
				(type default)
			)
			(layer "F.Fab")
		)
		(fp_line
			(start -0.12065 -0.305054)
			(end -0.12065 -0.2794)
			(stroke
				(width 0.1)
				(type default)
			)
			(layer "F.Fab")
		)
		(pad "1" smd circle
			(at -0.40005 0 270)
			(size 0 0)
			(layers "F.Cu" "F.Mask" "F.Paste")
			(net "IRQ_WAKE_R_N")
		)
		(pad "2" smd circle
			(at 0.40005 0 270)
			(size 0 0)
			(layers "F.Cu" "F.Mask" "F.Paste")
			(net "IRQ_WAKE_N")
		)
	)
	(footprint ""
		(layer "F.Cu")
		(at 183.679084 -355.898958 90)
		(property "Reference" "PR330"
			(at 0 0 90)
			(layer "F.SilkS")
			(hide yes)
			(effects
				(font
					(size 1.27 1.27)
				)
			)
		)
		(property "Value" ""
			(at 0 0 90)
			(layer "F.Fab")
			(effects
				(font
					(size 1.27 1.27)
				)
			)
		)
		(duplicate_pad_numbers_are_jumpers no)
		(fp_line
			(start 0.7874 -0.4064)
			(end 0.7874 0.4064)
			(stroke
				(width 0.1524)
				(type default)
			)
			(layer "F.SilkS")
		)
		(fp_line
			(start -0.7874 -0.4064)
			(end 0.7874 -0.4064)
			(stroke
				(width 0.1524)
				(type default)
			)
			(layer "F.SilkS")
		)
		(fp_line
			(start 0.7874 0.4064)
			(end -0.7874 0.4064)
			(stroke
				(width 0.1524)
				(type default)
			)
			(layer "F.SilkS")
		)
		(fp_line
			(start -0.7874 0.4064)
			(end -0.7874 -0.4064)
			(stroke
				(width 0.1524)
				(type default)
			)
			(layer "F.SilkS")
		)
		(fp_line
			(start -0.12065 -0.305054)
			(end -0.12065 -0.2794)
			(stroke
				(width 0.1)
				(type default)
			)
			(layer "F.Fab")
		)
		(fp_line
			(start -0.67945 -0.305054)
			(end -0.12065 -0.305054)
			(stroke
				(width 0.1)
				(type default)
			)
			(layer "F.Fab")
		)
		(fp_line
			(start 0.67945 -0.3048)
			(end 0.67945 0.3048)
			(stroke
				(width 0.1)
				(type default)
			)
			(layer "F.Fab")
		)
		(fp_line
			(start 0.12065 -0.3048)
			(end 0.67945 -0.3048)
			(stroke
				(width 0.1)
				(type default)
			)
			(layer "F.Fab")
		)
		(fp_line
			(start 0.12065 -0.2794)
			(end 0.12065 -0.3048)
			(stroke
				(width 0.1)
				(type default)
			)
			(layer "F.Fab")
		)
		(fp_line
			(start -0.12065 -0.2794)
			(end 0.12065 -0.2794)
			(stroke
				(width 0.1)
				(type default)
			)
			(layer "F.Fab")
		)
		(fp_line
			(start 0.120396 0.2794)
			(end -0.12065 0.2794)
			(stroke
				(width 0.1)
				(type default)
			)
			(layer "F.Fab")
		)
		(fp_line
			(start -0.12065 0.2794)
			(end -0.12065 0.3048)
			(stroke
				(width 0.1)
				(type default)
			)
			(layer "F.Fab")
		)
		(fp_line
			(start 0.67945 0.3048)
			(end 0.120396 0.3048)
			(stroke
				(width 0.1)
				(type default)
			)
			(layer "F.Fab")
		)
		(fp_line
			(start 0.120396 0.3048)
			(end 0.120396 0.2794)
			(stroke
				(width 0.1)
				(type default)
			)
			(layer "F.Fab")
		)
		(fp_line
			(start -0.12065 0.3048)
			(end -0.67945 0.3048)
			(stroke
				(width 0.1)
				(type default)
			)
			(layer "F.Fab")
		)
		(fp_line
			(start -0.67945 0.3048)
			(end -0.67945 -0.305054)
			(stroke
				(width 0.1)
				(type default)
			)
			(layer "F.Fab")
		)
		(pad "1" smd circle
			(at -0.40005 0 90)
			(size 0 0)
			(layers "F.Cu" "F.Mask" "F.Paste")
			(net "SW_PVDD11_S3_P1_BOOT1")
		)
		(pad "2" smd circle
			(at 0.40005 0 90)
			(size 0 0)
			(layers "F.Cu" "F.Mask" "F.Paste")
			(net "SW_PVDD11_S3_P1_BOOT1_RC")
		)
	)
	(footprint ""
		(layer "F.Cu")
		(at 18.865088 -373.44985 -90)
		(property "Reference" "PC6630"
			(at 4.41452 2.228088 0)
			(unlocked yes)
			(layer "F.SilkS")
			(effects
				(font
					(size 0.7874 0.5842)
					(thickness 0.1524)
				)
				(justify left)
			)
		)
		(property "Value" ""
			(at 0 0 270)
			(layer "F.Fab")
			(effects
				(font
					(size 1.27 1.27)
				)
			)
		)
		(duplicate_pad_numbers_are_jumpers no)
		(fp_line
			(start -1.988058 2.750058)
			(end 2.750058 2.750058)
			(stroke
				(width 0.1524)
				(type default)
			)
			(layer "F.SilkS")
		)
		(fp_line
			(start 2.750058 2.750058)
			(end 2.750058 0.9398)
			(stroke
				(width 0.1524)
				(type default)
			)
			(layer "F.SilkS")
		)
		(fp_line
			(start -2.750058 1.988058)
			(end -1.988058 2.750058)
			(stroke
				(width 0.1524)
				(type default)
			)
			(layer "F.SilkS")
		)
		(fp_line
			(start -2.750058 0.9398)
			(end -2.750058 1.988058)
			(stroke
				(width 0.1524)
				(type default)
			)
			(layer "F.SilkS")
		)
		(fp_line
			(start 2.750058 -0.9398)
			(end 2.750058 -2.750058)
			(stroke
				(width 0.1524)
				(type default)
			)
			(layer "F.SilkS")
		)
		(fp_line
			(start -2.750058 -1.988058)
			(end -2.750058 -0.9398)
			(stroke
				(width 0.1524)
				(type default)
			)
			(layer "F.SilkS")
		)
		(fp_line
			(start -1.988058 -2.750058)
			(end -2.750058 -1.988058)
			(stroke
				(width 0.1524)
				(type default)
			)
			(layer "F.SilkS")
		)
		(fp_line
			(start 2.750058 -2.750058)
			(end -1.988058 -2.750058)
			(stroke
				(width 0.1524)
				(type default)
			)
			(layer "F.SilkS")
		)
		(fp_line
			(start -2.750058 2.750058)
			(end 2.750058 2.750058)
			(stroke
				(width 0.1)
				(type default)
			)
			(layer "F.Fab")
		)
		(fp_line
			(start 2.750058 2.750058)
			(end 2.750058 -2.750058)
			(stroke
				(width 0.1)
				(type default)
			)
			(layer "F.Fab")
		)
		(fp_line
			(start -2.750058 -2.750058)
			(end -2.750058 2.750058)
			(stroke
				(width 0.1)
				(type default)
			)
			(layer "F.Fab")
		)
		(fp_line
			(start 2.750058 -2.750058)
			(end -2.750058 -2.750058)
			(stroke
				(width 0.1)
				(type default)
			)
			(layer "F.Fab")
		)
		(pad "1" smd rect
			(at -2.199894 0)
			(size 1.6002 3.0226)
			(layers "F.Cu" "F.Mask" "F.Paste")
			(net "P0V9_CPU1_RT_2D")
		)
		(pad "2" smd rect
			(at 2.199894 0)
			(size 1.6002 3.0226)
			(layers "F.Cu" "F.Mask" "F.Paste")
			(net "GND")
		)
	)
)
